# BASEBOARD_FAB2 (Tioga Pass) — schematic netlist excerpt (pin names and nets, part order shuffled) for the footprints in the layout excerpt that follows; sources: Cadence DE-HDL packaged netlist, KiCad conversion of Wiwynn_Tioga_Pass_MB.brd

C1D10  CAP  0.220UF 16V 10% X7R  pkg 0402  page 208 : A = VR_PVCCIN_CPU1_PH4_BOOT ; B = VR_PVCCIN_CPU1_PH4_PHASE
R4G14  RES  1.00K 1% CHIP  pkg 0402  page 233 : A = P3V3_STBY ; B = PWRGD_PVPP_GHJ_R
R7C6  RES  10M 1.0% CHIP  pkg 0603  page 114 : A = XTAL_33K_RTC1 ; B = XTAL_33K_RTC2

(kicad_pcb
	(version 20260206)
	(generator "pcbnew")
	(generator_version "10.0")
	(general
		(thickness 1.6)
		(legacy_teardrops no)
	)
	(paper "A4")
	(title_block
		(title "Wiwynn_Tioga_Pass_MB.brd")
		(comment 1 "Tioga Pass / footprints 966-968 of 4770")
	)
	(layers
		(0 "F.Cu" signal "TOP")
		(4 "In1.Cu" signal "L2GND")
		(6 "In2.Cu" signal "L3")
		(8 "In3.Cu" signal "L4GND")
		(10 "In4.Cu" signal "L5")
		(12 "In5.Cu" signal "L6GND")
		(14 "In6.Cu" signal "L7VCC")
		(16 "In7.Cu" signal "L8VCC")
		(18 "In8.Cu" signal "L9GND")
		(20 "In9.Cu" signal "L10")
		(22 "In10.Cu" signal "L11GND")
		(24 "In11.Cu" signal "L12")
		(26 "In12.Cu" signal "L13GND")
		(2 "B.Cu" signal "BOTTOM")
		(9 "F.Adhes" user "F.Adhesive")
		(11 "B.Adhes" user "B.Adhesive")
		(13 "F.Paste" user "Package Geometry/Pastemask Top")
		(15 "B.Paste" user "Package Geometry/Pastemask Bottom")
		(5 "F.SilkS" user "Ref Des/Silkscreen Top")
		(7 "B.SilkS" user "Ref Des/Silkscreen Bottom")
		(1 "F.Mask" user "Board Geometry/Soldermask Top")
		(3 "B.Mask" user "Board Geometry/Soldermask Bottom")
		(17 "Dwgs.User" user "User.Drawings")
		(19 "Cmts.User" user "User.Comments")
		(21 "Eco1.User" user "User.Eco1")
		(23 "Eco2.User" user "User.Eco2")
		(25 "Edge.Cuts" user "Board Geometry/Outline")
		(27 "Margin" user)
		(31 "F.CrtYd" user "Package Geometry/Place Bound Top")
		(29 "B.CrtYd" user "Package Geometry/Place Bound Bottom")
		(35 "F.Fab" user "Ref Des/Assembly Top")
		(33 "B.Fab" user "Ref Des/Assembly Bottom")
	)
	(footprint ""
		(layer "F.Cu")
		(at 369.2906 -99.2124)
		(property "Reference" "R7C6"
			(at 0 0 0)
			(layer "F.SilkS")
			(hide yes)
			(effects
				(font
					(size 1.27 1.27)
				)
			)
		)
		(property "Value" ""
			(at 0 0 0)
			(layer "F.Fab")
			(effects
				(font
					(size 1.27 1.27)
				)
			)
		)
		(duplicate_pad_numbers_are_jumpers no)
		(fp_poly
			(pts
				(xy -0.4953 -0.2032) (xy 0.4953 -0.2032) (xy 0.4953 1.6002) (xy -0.4953 1.6002)
			)
			(stroke
				(width 0)
				(type default)
			)
			(fill no)
			(layer "F.CrtYd")
		)
		(fp_line
			(start -0.4953 -0.2032)
			(end 0.4953 -0.2032)
			(stroke
				(width 0.1)
				(type default)
			)
			(layer "F.Fab")
		)
		(fp_line
			(start -0.4953 1.6002)
			(end -0.4953 -0.2032)
			(stroke
				(width 0.1)
				(type default)
			)
			(layer "F.Fab")
		)
		(fp_line
			(start 0.4953 -0.2032)
			(end 0.4953 1.6002)
			(stroke
				(width 0.1)
				(type default)
			)
			(layer "F.Fab")
		)
		(fp_line
			(start 0.4953 1.6002)
			(end -0.4953 1.6002)
			(stroke
				(width 0.1)
				(type default)
			)
			(layer "F.Fab")
		)
		(pad "1" smd rect
			(at 0 0)
			(size 0.762 0.889)
			(layers "F.Cu" "F.Mask" "F.Paste")
			(net "XTAL_33K_RTC1")
		)
		(pad "2" smd rect
			(at 0 1.397)
			(size 0.762 0.889)
			(layers "F.Cu" "F.Mask" "F.Paste")
			(net "XTAL_33K_RTC2")
		)
		(zone
			(layer "F.Cu")
			(hatch none 0.5)
			(connect_pads
				(clearance 0)
			)
			(min_thickness 0.25)
			(keepout
				(tracks not_allowed)
				(vias allowed)
				(pads allowed)
				(copperpour not_allowed)
				(footprints allowed)
			)
			(placement
				(enabled no)
				(sheetname "")
			)
			(fill
				(thermal_gap 0.5)
				(thermal_bridge_width 0.5)
				(island_removal_mode 0)
			)
			(polygon
				(pts
					(xy 368.9096 -98.2599) (xy 369.6716 -98.2599) (xy 369.6716 -98.7679) (xy 368.9096 -98.7679)
				)
			)
		)
		(zone
			(layer "F.Cu")
			(hatch none 0.5)
			(connect_pads
				(clearance 0)
			)
			(min_thickness 0.25)
			(keepout
				(tracks allowed)
				(vias not_allowed)
				(pads allowed)
				(copperpour not_allowed)
				(footprints allowed)
			)
			(placement
				(enabled no)
				(sheetname "")
			)
			(fill
				(thermal_gap 0.5)
				(thermal_bridge_width 0.5)
				(island_removal_mode 0)
			)
			(polygon
				(pts
					(xy 369.6716 -98.2599) (xy 369.6716 -98.7679) (xy 368.9096 -98.7679) (xy 368.9096 -98.2599)
				)
			)
		)
	)
	(footprint ""
		(layer "F.Cu")
		(at 28.829 -83.1342 90)
		(property "Reference" "C1D10"
			(at 0 0 90)
			(layer "F.SilkS")
			(hide yes)
			(effects
				(font
					(size 1.27 1.27)
				)
			)
		)
		(property "Value" ""
			(at 0 0 90)
			(layer "F.Fab")
			(effects
				(font
					(size 1.27 1.27)
				)
			)
		)
		(duplicate_pad_numbers_are_jumpers no)
		(fp_rect
			(start -0.3048 0.9906)
			(end 0.3048 -0.1016)
			(stroke
				(width 0)
				(type default)
			)
			(fill no)
			(layer "F.CrtYd")
		)
		(fp_line
			(start 0.3048 -0.1016)
			(end -0.3048 -0.1016)
			(stroke
				(width 0.1)
				(type default)
			)
			(layer "F.Fab")
		)
		(fp_line
			(start -0.3048 -0.1016)
			(end -0.3048 0.9906)
			(stroke
				(width 0.1)
				(type default)
			)
			(layer "F.Fab")
		)
		(fp_line
			(start 0.3048 0.9906)
			(end 0.3048 -0.1016)
			(stroke
				(width 0.1)
				(type default)
			)
			(layer "F.Fab")
		)
		(fp_line
			(start -0.3048 0.9906)
			(end 0.3048 0.9906)
			(stroke
				(width 0.1)
				(type default)
			)
			(layer "F.Fab")
		)
		(pad "1" smd rect
			(at 0 0 90)
			(size 0.508 0.508)
			(layers "F.Cu" "F.Mask" "F.Paste")
			(net "VR_PVCCIN_CPU1_PH4_BOOT")
		)
		(pad "2" smd rect
			(at 0 0.889 90)
			(size 0.508 0.508)
			(layers "F.Cu" "F.Mask" "F.Paste")
			(net "VR_PVCCIN_CPU1_PH4_PHASE")
		)
		(zone
			(layer "F.Cu")
			(hatch none 0.5)
			(connect_pads
				(clearance 0)
			)
			(min_thickness 0.25)
			(keepout
				(tracks not_allowed)
				(vias allowed)
				(pads allowed)
				(copperpour not_allowed)
				(footprints allowed)
			)
			(placement
				(enabled no)
				(sheetname "")
			)
			(fill
				(thermal_gap 0.5)
				(thermal_bridge_width 0.5)
				(island_removal_mode 0)
			)
			(polygon
				(pts
					(xy 29.464 -82.8802) (xy 29.464 -83.3882) (xy 29.083 -83.3882) (xy 29.083 -82.8802)
				)
			)
		)
		(zone
			(layer "F.Cu")
			(hatch none 0.5)
			(connect_pads
				(clearance 0)
			)
			(min_thickness 0.25)
			(keepout
				(tracks allowed)
				(vias not_allowed)
				(pads allowed)
				(copperpour not_allowed)
				(footprints allowed)
			)
			(placement
				(enabled no)
				(sheetname "")
			)
			(fill
				(thermal_gap 0.5)
				(thermal_bridge_width 0.5)
				(island_removal_mode 0)
			)
			(polygon
				(pts
					(xy 29.464 -82.8802) (xy 29.464 -83.3882) (xy 29.083 -83.3882) (xy 29.083 -82.8802)
				)
			)
		)
	)
	(footprint ""
		(layer "F.Cu")
		(at 179.959 -7.366 180)
		(property "Reference" "R4G14"
			(at 0 0 180)
			(layer "F.SilkS")
			(hide yes)
			(effects
				(font
					(size 1.27 1.27)
				)
			)
		)
		(property "Value" ""
			(at 0 0 180)
			(layer "F.Fab")
			(effects
				(font
					(size 1.27 1.27)
				)
			)
		)
		(duplicate_pad_numbers_are_jumpers no)
		(fp_rect
			(start 0.2794 -0.1016)
			(end -0.2794 0.9906)
			(stroke
				(width 0)
				(type default)
			)
			(fill no)
			(layer "F.CrtYd")
		)
		(fp_line
			(start 0.2794 0.9906)
			(end 0.2794 -0.1016)
			(stroke
				(width 0.1)
				(type default)
			)
			(layer "F.Fab")
		)
		(fp_line
			(start 0.2794 -0.1016)
			(end -0.2794 -0.1016)
			(stroke
				(width 0.1)
				(type default)
			)
			(layer "F.Fab")
		)
		(fp_line
			(start -0.2794 0.9906)
			(end 0.2794 0.9906)
			(stroke
				(width 0.1)
				(type default)
			)
			(layer "F.Fab")
		)
		(fp_line
			(start -0.2794 -0.1016)
			(end -0.2794 0.9906)
			(stroke
				(width 0.1)
				(type default)
			)
			(layer "F.Fab")
		)
		(pad "1" smd rect
			(at 0 0 180)
			(size 0.508 0.508)
			(layers "F.Cu" "F.Mask" "F.Paste")
			(net "P3V3_STBY")
		)
		(pad "2" smd rect
			(at 0 0.889 180)
			(size 0.508 0.508)
			(layers "F.Cu" "F.Mask" "F.Paste")
			(net "PWRGD_PVPP_GHJ_R")
		)
		(zone
			(layer "F.Cu")
			(hatch none 0.5)
			(connect_pads
				(clearance 0)
			)
			(min_thickness 0.25)
			(keepout
				(tracks not_allowed)
				(vias allowed)
				(pads allowed)
				(copperpour not_allowed)
				(footprints allowed)
			)
			(placement
				(enabled no)
				(sheetname "")
			)
			(fill
				(thermal_gap 0.5)
				(thermal_bridge_width 0.5)
				(island_removal_mode 0)
			)
			(polygon
				(pts
					(xy 179.705 -7.62) (xy 180.213 -7.62) (xy 180.213 -8.001) (xy 179.705 -8.001)
				)
			)
		)
		(zone
			(layer "F.Cu")
			(hatch none 0.5)
			(connect_pads
				(clearance 0)
			)
			(min_thickness 0.25)
			(keepout
				(tracks allowed)
				(vias not_allowed)
				(pads allowed)
				(copperpour not_allowed)
				(footprints allowed)
			)
			(placement
				(enabled no)
				(sheetname "")
			)
			(fill
				(thermal_gap 0.5)
				(thermal_bridge_width 0.5)
				(island_removal_mode 0)
			)
			(polygon
				(pts
					(xy 179.705 -7.62) (xy 180.213 -7.62) (xy 180.213 -8.001) (xy 179.705 -8.001)
				)
			)
		)
	)
)
